# T6G (Grand Teton) — schematic netlist excerpt (pin names and nets, part order shuffled) for the footprints in the layout excerpt that follows; sources: Cadence DE-HDL packaged netlist, KiCad conversion of 04192023_DAF0TMB3IC0_F0TG_MB_C_brd_V02_OCP.brd

PC6504  Q_CAP  22UF 16V 20% X6S  pkg C0805  page 360 : A = SW_P12V_AUX_P1V8_RETIMER_CPU0_FLT ; B = GND
PR3967  Q_RES  10 1% CHIP  pkg 0402LF  page 146 : A = P3V3_AUX ; B = P3V3_E1S_VCC_0
R2663  Q_RES  33.2 1% CHIP  pkg 0402LF  page 81 : A = FM_SWB_PWRGD_ISO_R ; B = FM_SWB_PWRGD_ISO

(kicad_pcb
	(version 20260206)
	(generator "pcbnew")
	(generator_version "10.0")
	(general
		(thickness 1.6)
		(legacy_teardrops no)
	)
	(paper "A4")
	(title_block
		(title "04192023_DAF0TMB3IC0_F0TG_MB_C_brd_V02_OCP.brd")
		(comment 1 "Grand Teton / footprints 1075-1077 of 8354")
	)
	(layers
		(0 "F.Cu" signal "TOP")
		(4 "In1.Cu" signal "GND")
		(6 "In2.Cu" signal "IN1")
		(8 "In3.Cu" signal "GND1")
		(10 "In4.Cu" signal "IN2")
		(12 "In5.Cu" signal "GND2")
		(14 "In6.Cu" signal "IN3")
		(16 "In7.Cu" signal "GND3")
		(18 "In8.Cu" signal "VCC")
		(20 "In9.Cu" signal "VCC1")
		(22 "In10.Cu" signal "GND4")
		(24 "In11.Cu" signal "IN4")
		(26 "In12.Cu" signal "GND5")
		(28 "In13.Cu" signal "IN5")
		(30 "In14.Cu" signal "GND6")
		(32 "In15.Cu" signal "IN6")
		(34 "In16.Cu" signal "GND7")
		(2 "B.Cu" signal "BOTTOM")
		(9 "F.Adhes" user "F.Adhesive")
		(11 "B.Adhes" user "B.Adhesive")
		(13 "F.Paste" user "Package Geometry/Pastemask Top")
		(15 "B.Paste" user "Package Geometry/Pastemask Bottom")
		(5 "F.SilkS" user "Ref Des/Silkscreen Top")
		(7 "B.SilkS" user "Ref Des/Silkscreen Bottom")
		(1 "F.Mask" user "Board Geometry/Soldermask Top")
		(3 "B.Mask" user "Board Geometry/Soldermask Bottom")
		(17 "Dwgs.User" user "User.Drawings")
		(19 "Cmts.User" user "User.Comments")
		(21 "Eco1.User" user "User.Eco1")
		(23 "Eco2.User" user "User.Eco2")
		(25 "Edge.Cuts" user "Board Geometry/Outline")
		(27 "Margin" user)
		(31 "F.CrtYd" user "Package Geometry/Place Bound Top")
		(29 "B.CrtYd" user "Package Geometry/Place Bound Bottom")
		(35 "F.Fab" user "Ref Des/Assembly Top")
		(33 "B.Fab" user "Ref Des/Assembly Bottom")
	)
	(footprint ""
		(layer "F.Cu")
		(at 220.363034 -75.02779 -90)
		(property "Reference" "PR3967"
			(at 0 0 270)
			(layer "F.SilkS")
			(hide yes)
			(effects
				(font
					(size 1.27 1.27)
				)
			)
		)
		(property "Value" ""
			(at 0 0 270)
			(layer "F.Fab")
			(effects
				(font
					(size 1.27 1.27)
				)
			)
		)
		(duplicate_pad_numbers_are_jumpers no)
		(fp_line
			(start -0.7874 0.4064)
			(end -0.7874 -0.4064)
			(stroke
				(width 0.1524)
				(type default)
			)
			(layer "F.SilkS")
		)
		(fp_line
			(start 0.7874 0.4064)
			(end -0.7874 0.4064)
			(stroke
				(width 0.1524)
				(type default)
			)
			(layer "F.SilkS")
		)
		(fp_line
			(start -0.7874 -0.4064)
			(end 0.7874 -0.4064)
			(stroke
				(width 0.1524)
				(type default)
			)
			(layer "F.SilkS")
		)
		(fp_line
			(start 0.7874 -0.4064)
			(end 0.7874 0.4064)
			(stroke
				(width 0.1524)
				(type default)
			)
			(layer "F.SilkS")
		)
		(fp_line
			(start -0.67945 0.3048)
			(end -0.67945 -0.305054)
			(stroke
				(width 0.1)
				(type default)
			)
			(layer "F.Fab")
		)
		(fp_line
			(start -0.12065 0.3048)
			(end -0.67945 0.3048)
			(stroke
				(width 0.1)
				(type default)
			)
			(layer "F.Fab")
		)
		(fp_line
			(start 0.120396 0.3048)
			(end 0.120396 0.2794)
			(stroke
				(width 0.1)
				(type default)
			)
			(layer "F.Fab")
		)
		(fp_line
			(start 0.67945 0.3048)
			(end 0.120396 0.3048)
			(stroke
				(width 0.1)
				(type default)
			)
			(layer "F.Fab")
		)
		(fp_line
			(start -0.12065 0.2794)
			(end -0.12065 0.3048)
			(stroke
				(width 0.1)
				(type default)
			)
			(layer "F.Fab")
		)
		(fp_line
			(start 0.120396 0.2794)
			(end -0.12065 0.2794)
			(stroke
				(width 0.1)
				(type default)
			)
			(layer "F.Fab")
		)
		(fp_line
			(start -0.12065 -0.2794)
			(end 0.12065 -0.2794)
			(stroke
				(width 0.1)
				(type default)
			)
			(layer "F.Fab")
		)
		(fp_line
			(start 0.12065 -0.2794)
			(end 0.12065 -0.3048)
			(stroke
				(width 0.1)
				(type default)
			)
			(layer "F.Fab")
		)
		(fp_line
			(start 0.12065 -0.3048)
			(end 0.67945 -0.3048)
			(stroke
				(width 0.1)
				(type default)
			)
			(layer "F.Fab")
		)
		(fp_line
			(start 0.67945 -0.3048)
			(end 0.67945 0.3048)
			(stroke
				(width 0.1)
				(type default)
			)
			(layer "F.Fab")
		)
		(fp_line
			(start -0.67945 -0.305054)
			(end -0.12065 -0.305054)
			(stroke
				(width 0.1)
				(type default)
			)
			(layer "F.Fab")
		)
		(fp_line
			(start -0.12065 -0.305054)
			(end -0.12065 -0.2794)
			(stroke
				(width 0.1)
				(type default)
			)
			(layer "F.Fab")
		)
		(pad "1" smd circle
			(at -0.40005 0 270)
			(size 0 0)
			(layers "F.Cu" "F.Mask" "F.Paste")
			(net "P3V3_AUX")
		)
		(pad "2" smd circle
			(at 0.40005 0 270)
			(size 0 0)
			(layers "F.Cu" "F.Mask" "F.Paste")
			(net "P3V3_E1S_VCC_0")
		)
	)
	(footprint ""
		(layer "F.Cu")
		(at 240.792 -281.7368 180)
		(property "Reference" "PC6504"
			(at 0 0 180)
			(layer "F.SilkS")
			(hide yes)
			(effects
				(font
					(size 1.27 1.27)
				)
			)
		)
		(property "Value" ""
			(at 0 0 180)
			(layer "F.Fab")
			(effects
				(font
					(size 1.27 1.27)
				)
			)
		)
		(duplicate_pad_numbers_are_jumpers no)
		(fp_line
			(start 1.524 0.762)
			(end -1.524 0.762)
			(stroke
				(width 0.1524)
				(type default)
			)
			(layer "F.SilkS")
		)
		(fp_line
			(start 1.524 -0.762)
			(end 1.524 0.762)
			(stroke
				(width 0.1524)
				(type default)
			)
			(layer "F.SilkS")
		)
		(fp_line
			(start -1.524 0.762)
			(end -1.524 -0.762)
			(stroke
				(width 0.1524)
				(type default)
			)
			(layer "F.SilkS")
		)
		(fp_line
			(start -1.524 -0.762)
			(end 1.524 -0.762)
			(stroke
				(width 0.1524)
				(type default)
			)
			(layer "F.SilkS")
		)
		(fp_line
			(start 1.1049 0.724916)
			(end 1.1049 -0.724916)
			(stroke
				(width 0.1)
				(type default)
			)
			(layer "F.Fab")
		)
		(fp_line
			(start 1.1049 -0.724916)
			(end -1.1049 -0.724916)
			(stroke
				(width 0.1)
				(type default)
			)
			(layer "F.Fab")
		)
		(fp_line
			(start -1.1049 0.724916)
			(end 1.1049 0.724916)
			(stroke
				(width 0.1)
				(type default)
			)
			(layer "F.Fab")
		)
		(fp_line
			(start -1.1049 -0.724916)
			(end -1.1049 0.724916)
			(stroke
				(width 0.1)
				(type default)
			)
			(layer "F.Fab")
		)
		(pad "1" smd rect
			(at -0.889 0)
			(size 1.016 1.27)
			(layers "F.Cu" "F.Mask" "F.Paste")
			(net "SW_P12V_AUX_P1V8_RETIMER_CPU0_FLT")
		)
		(pad "2" smd rect
			(at 0.889 0)
			(size 1.016 1.27)
			(layers "F.Cu" "F.Mask" "F.Paste")
			(net "GND")
		)
	)
	(footprint ""
		(layer "F.Cu")
		(at 205.232508 -124.801376)
		(property "Reference" "R2663"
			(at 0 0 0)
			(layer "F.SilkS")
			(hide yes)
			(effects
				(font
					(size 1.27 1.27)
				)
			)
		)
		(property "Value" ""
			(at 0 0 0)
			(layer "F.Fab")
			(effects
				(font
					(size 1.27 1.27)
				)
			)
		)
		(duplicate_pad_numbers_are_jumpers no)
		(fp_line
			(start -0.7874 -0.4064)
			(end 0.7874 -0.4064)
			(stroke
				(width 0.1524)
				(type default)
			)
			(layer "F.SilkS")
		)
		(fp_line
			(start -0.7874 0.4064)
			(end -0.7874 -0.4064)
			(stroke
				(width 0.1524)
				(type default)
			)
			(layer "F.SilkS")
		)
		(fp_line
			(start 0.7874 -0.4064)
			(end 0.7874 0.4064)
			(stroke
				(width 0.1524)
				(type default)
			)
			(layer "F.SilkS")
		)
		(fp_line
			(start 0.7874 0.4064)
			(end -0.7874 0.4064)
			(stroke
				(width 0.1524)
				(type default)
			)
			(layer "F.SilkS")
		)
		(fp_line
			(start -0.67945 -0.305054)
			(end -0.12065 -0.305054)
			(stroke
				(width 0.1)
				(type default)
			)
			(layer "F.Fab")
		)
		(fp_line
			(start -0.67945 0.3048)
			(end -0.67945 -0.305054)
			(stroke
				(width 0.1)
				(type default)
			)
			(layer "F.Fab")
		)
		(fp_line
			(start -0.12065 -0.305054)
			(end -0.12065 -0.2794)
			(stroke
				(width 0.1)
				(type default)
			)
			(layer "F.Fab")
		)
		(fp_line
			(start -0.12065 -0.2794)
			(end 0.12065 -0.2794)
			(stroke
				(width 0.1)
				(type default)
			)
			(layer "F.Fab")
		)
		(fp_line
			(start -0.12065 0.2794)
			(end -0.12065 0.3048)
			(stroke
				(width 0.1)
				(type default)
			)
			(layer "F.Fab")
		)
		(fp_line
			(start -0.12065 0.3048)
			(end -0.67945 0.3048)
			(stroke
				(width 0.1)
				(type default)
			)
			(layer "F.Fab")
		)
		(fp_line
			(start 0.120396 0.2794)
			(end -0.12065 0.2794)
			(stroke
				(width 0.1)
				(type default)
			)
			(layer "F.Fab")
		)
		(fp_line
			(start 0.120396 0.3048)
			(end 0.120396 0.2794)
			(stroke
				(width 0.1)
				(type default)
			)
			(layer "F.Fab")
		)
		(fp_line
			(start 0.12065 -0.3048)
			(end 0.67945 -0.3048)
			(stroke
				(width 0.1)
				(type default)
			)
			(layer "F.Fab")
		)
		(fp_line
			(start 0.12065 -0.2794)
			(end 0.12065 -0.3048)
			(stroke
				(width 0.1)
				(type default)
			)
			(layer "F.Fab")
		)
		(fp_line
			(start 0.67945 -0.3048)
			(end 0.67945 0.3048)
			(stroke
				(width 0.1)
				(type default)
			)
			(layer "F.Fab")
		)
		(fp_line
			(start 0.67945 0.3048)
			(end 0.120396 0.3048)
			(stroke
				(width 0.1)
				(type default)
			)
			(layer "F.Fab")
		)
		(pad "1" smd circle
			(at -0.40005 0)
			(size 0 0)
			(layers "F.Cu" "F.Mask" "F.Paste")
			(net "FM_SWB_PWRGD_ISO_R")
		)
		(pad "2" smd circle
			(at 0.40005 0)
			(size 0 0)
			(layers "F.Cu" "F.Mask" "F.Paste")
			(net "FM_SWB_PWRGD_ISO")
		)
	)
)
